# S9S_MB_2U (Grand Teton) — schematic netlist excerpt (pin names and nets, part order shuffled) for the footprints in the layout excerpt that follows; sources: Cadence DE-HDL packaged netlist, KiCad conversion of 03242023_DA0F0TMBIJ0_F0T_Motherboard_J_brd_V01_OCP.brd

R915  Q_RES  0 5% CHIP  pkg 0402LF  page 185 : A = SPI_PCH_IO0 ; B = SPI_SYS_MOSI
R76  Q_RES  35.7K 1% CHIP  pkg 0402LF  page 109 : A = PD_CHF_CPU1_DIMM2_SAA ; B = GND

(kicad_pcb
	(version 20260206)
	(generator "pcbnew")
	(generator_version "10.0")
	(general
		(thickness 1.6)
		(legacy_teardrops no)
	)
	(paper "A4")
	(title_block
		(title "03242023_DA0F0TMBIJ0_F0T_Motherboard_J_brd_V01_OCP.brd")
		(comment 1 "Grand Teton / footprints 4222-4223 of 6105")
	)
	(layers
		(0 "F.Cu" signal "TOP")
		(4 "In1.Cu" signal "GND")
		(6 "In2.Cu" signal "IN1")
		(8 "In3.Cu" signal "GND1")
		(10 "In4.Cu" signal "IN2")
		(12 "In5.Cu" signal "GND2")
		(14 "In6.Cu" signal "IN3")
		(16 "In7.Cu" signal "GND3")
		(18 "In8.Cu" signal "VCC")
		(20 "In9.Cu" signal "VCC1")
		(22 "In10.Cu" signal "GND4")
		(24 "In11.Cu" signal "IN4")
		(26 "In12.Cu" signal "GND5")
		(28 "In13.Cu" signal "IN5")
		(30 "In14.Cu" signal "GND6")
		(32 "In15.Cu" signal "IN6")
		(34 "In16.Cu" signal "GND7")
		(2 "B.Cu" signal "BOTTOM")
		(9 "F.Adhes" user "F.Adhesive")
		(11 "B.Adhes" user "B.Adhesive")
		(13 "F.Paste" user "Package Geometry/Pastemask Top")
		(15 "B.Paste" user "Package Geometry/Pastemask Bottom")
		(5 "F.SilkS" user "Ref Des/Silkscreen Top")
		(7 "B.SilkS" user "Ref Des/Silkscreen Bottom")
		(1 "F.Mask" user "Board Geometry/Soldermask Top")
		(3 "B.Mask" user "Board Geometry/Soldermask Bottom")
		(17 "Dwgs.User" user "User.Drawings")
		(19 "Cmts.User" user "User.Comments")
		(21 "Eco1.User" user "User.Eco1")
		(23 "Eco2.User" user "User.Eco2")
		(25 "Edge.Cuts" user "Board Geometry/Outline")
		(27 "Margin" user)
		(31 "F.CrtYd" user "Package Geometry/Place Bound Top")
		(29 "B.CrtYd" user "Package Geometry/Place Bound Bottom")
		(35 "F.Fab" user "Ref Des/Assembly Top")
		(33 "B.Fab" user "Ref Des/Assembly Bottom")
	)
	(footprint ""
		(layer "B.Cu")
		(at 333.824326 -31.397702 90)
		(property "Reference" "R915"
			(at 0 0 90)
			(layer "B.SilkS")
			(hide yes)
			(effects
				(font
					(size 1.27 1.27)
				)
				(justify mirror)
			)
		)
		(property "Value" ""
			(at 0 0 90)
			(layer "B.Fab")
			(effects
				(font
					(size 1.27 1.27)
				)
				(justify mirror)
			)
		)
		(duplicate_pad_numbers_are_jumpers no)
		(fp_line
			(start 0.7874 -0.4064)
			(end -0.7874 -0.4064)
			(stroke
				(width 0.1524)
				(type default)
			)
			(layer "B.SilkS")
		)
		(fp_line
			(start -0.7874 -0.4064)
			(end -0.7874 0.4064)
			(stroke
				(width 0.1524)
				(type default)
			)
			(layer "B.SilkS")
		)
		(fp_line
			(start 0.7874 0.4064)
			(end 0.7874 -0.4064)
			(stroke
				(width 0.1524)
				(type default)
			)
			(layer "B.SilkS")
		)
		(fp_line
			(start -0.7874 0.4064)
			(end 0.7874 0.4064)
			(stroke
				(width 0.1524)
				(type default)
			)
			(layer "B.SilkS")
		)
		(fp_line
			(start 0.67945 -0.305054)
			(end 0.12065 -0.305054)
			(stroke
				(width 0.1)
				(type default)
			)
			(layer "B.Fab")
		)
		(fp_line
			(start 0.12065 -0.305054)
			(end 0.12065 -0.2794)
			(stroke
				(width 0.1)
				(type default)
			)
			(layer "B.Fab")
		)
		(fp_line
			(start -0.12065 -0.3048)
			(end -0.67945 -0.3048)
			(stroke
				(width 0.1)
				(type default)
			)
			(layer "B.Fab")
		)
		(fp_line
			(start -0.67945 -0.3048)
			(end -0.67945 0.3048)
			(stroke
				(width 0.1)
				(type default)
			)
			(layer "B.Fab")
		)
		(fp_line
			(start 0.12065 -0.2794)
			(end -0.12065 -0.2794)
			(stroke
				(width 0.1)
				(type default)
			)
			(layer "B.Fab")
		)
		(fp_line
			(start -0.12065 -0.2794)
			(end -0.12065 -0.3048)
			(stroke
				(width 0.1)
				(type default)
			)
			(layer "B.Fab")
		)
		(fp_line
			(start 0.12065 0.2794)
			(end 0.12065 0.3048)
			(stroke
				(width 0.1)
				(type default)
			)
			(layer "B.Fab")
		)
		(fp_line
			(start -0.120396 0.2794)
			(end 0.12065 0.2794)
			(stroke
				(width 0.1)
				(type default)
			)
			(layer "B.Fab")
		)
		(fp_line
			(start 0.67945 0.3048)
			(end 0.67945 -0.305054)
			(stroke
				(width 0.1)
				(type default)
			)
			(layer "B.Fab")
		)
		(fp_line
			(start 0.12065 0.3048)
			(end 0.67945 0.3048)
			(stroke
				(width 0.1)
				(type default)
			)
			(layer "B.Fab")
		)
		(fp_line
			(start -0.120396 0.3048)
			(end -0.120396 0.2794)
			(stroke
				(width 0.1)
				(type default)
			)
			(layer "B.Fab")
		)
		(fp_line
			(start -0.67945 0.3048)
			(end -0.120396 0.3048)
			(stroke
				(width 0.1)
				(type default)
			)
			(layer "B.Fab")
		)
		(pad "1" smd circle
			(at 0.40005 0 270)
			(size 0 0)
			(layers "B.Cu" "B.Mask" "B.Paste")
			(net "SPI_PCH_IO0")
		)
		(pad "2" smd circle
			(at -0.40005 0 270)
			(size 0 0)
			(layers "B.Cu" "B.Mask" "B.Paste")
			(net "SPI_SYS_MOSI")
		)
	)
	(footprint ""
		(layer "B.Cu")
		(at 175.9712 -319.293748)
		(property "Reference" "R76"
			(at 0 0 0)
			(layer "B.SilkS")
			(hide yes)
			(effects
				(font
					(size 1.27 1.27)
				)
				(justify mirror)
			)
		)
		(property "Value" ""
			(at 0 0 0)
			(layer "B.Fab")
			(effects
				(font
					(size 1.27 1.27)
				)
				(justify mirror)
			)
		)
		(duplicate_pad_numbers_are_jumpers no)
		(fp_line
			(start -0.7874 -0.4064)
			(end -0.7874 0.4064)
			(stroke
				(width 0.1524)
				(type default)
			)
			(layer "B.SilkS")
		)
		(fp_line
			(start -0.7874 0.4064)
			(end 0.7874 0.4064)
			(stroke
				(width 0.1524)
				(type default)
			)
			(layer "B.SilkS")
		)
		(fp_line
			(start 0.7874 -0.4064)
			(end -0.7874 -0.4064)
			(stroke
				(width 0.1524)
				(type default)
			)
			(layer "B.SilkS")
		)
		(fp_line
			(start 0.7874 0.4064)
			(end 0.7874 -0.4064)
			(stroke
				(width 0.1524)
				(type default)
			)
			(layer "B.SilkS")
		)
		(fp_line
			(start -0.67945 -0.3048)
			(end -0.67945 0.3048)
			(stroke
				(width 0.1)
				(type default)
			)
			(layer "B.Fab")
		)
		(fp_line
			(start -0.67945 0.3048)
			(end -0.120396 0.3048)
			(stroke
				(width 0.1)
				(type default)
			)
			(layer "B.Fab")
		)
		(fp_line
			(start -0.12065 -0.3048)
			(end -0.67945 -0.3048)
			(stroke
				(width 0.1)
				(type default)
			)
			(layer "B.Fab")
		)
		(fp_line
			(start -0.12065 -0.2794)
			(end -0.12065 -0.3048)
			(stroke
				(width 0.1)
				(type default)
			)
			(layer "B.Fab")
		)
		(fp_line
			(start -0.120396 0.2794)
			(end 0.12065 0.2794)
			(stroke
				(width 0.1)
				(type default)
			)
			(layer "B.Fab")
		)
		(fp_line
			(start -0.120396 0.3048)
			(end -0.120396 0.2794)
			(stroke
				(width 0.1)
				(type default)
			)
			(layer "B.Fab")
		)
		(fp_line
			(start 0.12065 -0.305054)
			(end 0.12065 -0.2794)
			(stroke
				(width 0.1)
				(type default)
			)
			(layer "B.Fab")
		)
		(fp_line
			(start 0.12065 -0.2794)
			(end -0.12065 -0.2794)
			(stroke
				(width 0.1)
				(type default)
			)
			(layer "B.Fab")
		)
		(fp_line
			(start 0.12065 0.2794)
			(end 0.12065 0.3048)
			(stroke
				(width 0.1)
				(type default)
			)
			(layer "B.Fab")
		)
		(fp_line
			(start 0.12065 0.3048)
			(end 0.67945 0.3048)
			(stroke
				(width 0.1)
				(type default)
			)
			(layer "B.Fab")
		)
		(fp_line
			(start 0.67945 -0.305054)
			(end 0.12065 -0.305054)
			(stroke
				(width 0.1)
				(type default)
			)
			(layer "B.Fab")
		)
		(fp_line
			(start 0.67945 0.3048)
			(end 0.67945 -0.305054)
			(stroke
				(width 0.1)
				(type default)
			)
			(layer "B.Fab")
		)
		(pad "1" smd circle
			(at 0.40005 0 180)
			(size 0 0)
			(layers "B.Cu" "B.Mask" "B.Paste")
			(net "PD_CHF_CPU1_DIMM2_SAA")
		)
		(pad "2" smd circle
			(at -0.40005 0 180)
			(size 0 0)
			(layers "B.Cu" "B.Mask" "B.Paste")
			(net "GND")
		)
	)
)
